(kicad_pcb
	(version 20221018)
	(generator pcbnew)
	(general
    (thickness 1.62)
  )
	(paper "A4")
	(title_block
    (title "ECP5 - Datacenter Secure Control Module (DC-SCM)")
    (date "2024-07-01")
    (rev "1.2.1")
		(comment 9 "footprint 50 of 506 (U21), pads 702-756 of 756")
	)
	(layers
    (0 "F.Cu" signal)
    (1 "In1.Cu" power)
    (2 "In2.Cu" signal)
    (3 "In3.Cu" power)
    (4 "In4.Cu" power)
    (5 "In5.Cu" signal)
    (6 "In6.Cu" power)
    (31 "B.Cu" signal)
    (32 "B.Adhes" user "B.Adhesive")
    (33 "F.Adhes" user "F.Adhesive")
    (34 "B.Paste" user)
    (35 "F.Paste" user)
    (36 "B.SilkS" user "B.Silkscreen")
    (37 "F.SilkS" user "F.Silkscreen")
    (38 "B.Mask" user)
    (39 "F.Mask" user)
    (40 "Dwgs.User" user "User.Drawings")
    (41 "Cmts.User" user "User.Comments")
    (42 "Eco1.User" user "User.Eco1")
    (43 "Eco2.User" user "User.Eco2")
    (44 "Edge.Cuts" user)
    (45 "Margin" user)
    (46 "B.CrtYd" user "B.Courtyard")
    (47 "F.CrtYd" user "F.Courtyard")
    (48 "B.Fab" user)
    (49 "F.Fab" user)
  )
	(footprint "antmicro-footprints:BGA-1024-756_27x27mm_Layout32x32_P0.8mm" locked
    (layer "F.Cu")
    (at 104.4 120.55)
    (property "Author" "Antmicro")
    (property "License" "Apache-2.0")
    (property "MPN" "LFE5UM5G-85F-8BG756C")
    (property "Manufacturer" "Lattice Semiconductor")
    (property "Sheetfile" "fpga-power-supply.kicad_sch")
    (property "Sheetname" "FPGA power supply")
    (property "ki_description" "ECP5-5G Field Programmable Gate Array")
    (property "ki_keywords" "SMT, FPGA, IC")
    (attr smd)
    (fp_text reference "U21" (at -12.97 -14.53) (layer "F.SilkS")
        (effects (font (size 0.7 0.7) (thickness 0.127)))
    )
    (fp_text value "ECP5UM5G_85_CABGA756" (at 0 14.5) (layer "F.Fab")
        (effects (font (size 1 1) (thickness 0.15)))
    )
    (pad "V32" smd circle locked (at 12.4 1.2) (size 0.4 0.4) (layers "F.Cu" "F.Paste" "F.Mask")
      (net 340 "ULPI1_D2") (pinfunction "PR68C") (pintype "bidirectional"))
    (pad "W1" smd circle locked (at -12.4 2) (size 0.4 0.4) (layers "F.Cu" "F.Paste" "F.Mask")
      (net 768 "unconnected-(U21G-PL68D-PadW1)") (pinfunction "PL68D") (pintype "bidirectional+no_connect"))
    (pad "W2" smd circle locked (at -11.6 2) (size 0.4 0.4) (layers "F.Cu" "F.Paste" "F.Mask")
      (net 254 "DDR3_CAS") (pinfunction "PL86A") (pintype "bidirectional"))
    (pad "W3" smd circle locked (at -10.8 2) (size 0.4 0.4) (layers "F.Cu" "F.Paste" "F.Mask")
      (net 769 "unconnected-(U21G-PL65C-PadW3)") (pinfunction "PL65C") (pintype "bidirectional+no_connect"))
    (pad "W4" smd circle locked (at -10 2) (size 0.4 0.4) (layers "F.Cu" "F.Paste" "F.Mask")
      (net 246 "DDR3_A0") (pinfunction "PL74B") (pintype "bidirectional"))
    (pad "W5" smd circle locked (at -9.2 2) (size 0.4 0.4) (layers "F.Cu" "F.Paste" "F.Mask")
      (net 252 "DDR3_BA2") (pinfunction "PL71D") (pintype "bidirectional"))
    (pad "W6" smd circle locked (at -8.4 2) (size 0.4 0.4) (layers "F.Cu" "F.Paste" "F.Mask")
      (net 770 "unconnected-(U21A-NC-PadW6)") (pinfunction "NC") (pintype "no_connect"))
    (pad "W10" smd circle locked (at -5.2 2) (size 0.4 0.4) (layers "F.Cu" "F.Paste" "F.Mask")
      (net 3 "VCC1V35") (pinfunction "VCCIO6") (pintype "passive"))
    (pad "W11" smd circle locked (at -4.4 2) (size 0.4 0.4) (layers "F.Cu" "F.Paste" "F.Mask")
      (net 1 "GND") (pinfunction "GND") (pintype "passive"))
    (pad "W12" smd circle locked (at -3.6 2) (size 0.4 0.4) (layers "F.Cu" "F.Paste" "F.Mask")
      (net 211 "VCC1V2") (pinfunction "VCC") (pintype "passive"))
    (pad "W13" smd circle locked (at -2.8 2) (size 0.4 0.4) (layers "F.Cu" "F.Paste" "F.Mask")
      (net 1 "GND") (pinfunction "GND") (pintype "passive"))
    (pad "W14" smd circle locked (at -2 2) (size 0.4 0.4) (layers "F.Cu" "F.Paste" "F.Mask")
      (net 1 "GND") (pinfunction "GND") (pintype "passive"))
    (pad "W15" smd circle locked (at -1.2 2) (size 0.4 0.4) (layers "F.Cu" "F.Paste" "F.Mask")
      (net 1 "GND") (pinfunction "GND") (pintype "passive"))
    (pad "W16" smd circle locked (at -0.4 2) (size 0.4 0.4) (layers "F.Cu" "F.Paste" "F.Mask")
      (net 1 "GND") (pinfunction "GND") (pintype "passive"))
    (pad "W17" smd circle locked (at 0.4 2) (size 0.4 0.4) (layers "F.Cu" "F.Paste" "F.Mask")
      (net 1 "GND") (pinfunction "GND") (pintype "passive"))
    (pad "W18" smd circle locked (at 1.2 2) (size 0.4 0.4) (layers "F.Cu" "F.Paste" "F.Mask")
      (net 1 "GND") (pinfunction "GND") (pintype "passive"))
    (pad "W19" smd circle locked (at 2 2) (size 0.4 0.4) (layers "F.Cu" "F.Paste" "F.Mask")
      (net 1 "GND") (pinfunction "GND") (pintype "passive"))
    (pad "W20" smd circle locked (at 2.8 2) (size 0.4 0.4) (layers "F.Cu" "F.Paste" "F.Mask")
      (net 1 "GND") (pinfunction "GND") (pintype "passive"))
    (pad "W21" smd circle locked (at 3.6 2) (size 0.4 0.4) (layers "F.Cu" "F.Paste" "F.Mask")
      (net 211 "VCC1V2") (pinfunction "VCC") (pintype "passive"))
    (pad "W22" smd circle locked (at 4.4 2) (size 0.4 0.4) (layers "F.Cu" "F.Paste" "F.Mask")
      (net 1 "GND") (pinfunction "GND") (pintype "passive"))
    (pad "W23" smd circle locked (at 5.2 2) (size 0.4 0.4) (layers "F.Cu" "F.Paste" "F.Mask")
      (net 2 "VCC3V3") (pinfunction "VCCIO3") (pintype "passive"))
    (pad "W27" smd circle locked (at 8.4 2) (size 0.4 0.4) (layers "F.Cu" "F.Paste" "F.Mask")
      (net 771 "unconnected-(U21A-NC-PadW27)") (pinfunction "NC") (pintype "no_connect"))
    (pad "W28" smd circle locked (at 9.2 2) (size 0.4 0.4) (layers "F.Cu" "F.Paste" "F.Mask")
      (net 772 "unconnected-(U21E-PR71D-PadW28)") (pinfunction "PR71D") (pintype "bidirectional+no_connect"))
    (pad "W29" smd circle locked (at 10 2) (size 0.4 0.4) (layers "F.Cu" "F.Paste" "F.Mask")
      (net 773 "unconnected-(U21E-PR74B-PadW29)") (pinfunction "PR74B") (pintype "bidirectional+no_connect"))
    (pad "W30" smd circle locked (at 10.8 2) (size 0.4 0.4) (layers "F.Cu" "F.Paste" "F.Mask")
      (net 116 "DBP_PRDY_N") (pinfunction "PR65C") (pintype "bidirectional"))
    (pad "W31" smd circle locked (at 11.6 2) (size 0.4 0.4) (layers "F.Cu" "F.Paste" "F.Mask")
      (net 342 "ULPI1_D0") (pinfunction "PR86A") (pintype "bidirectional"))
    (pad "W32" smd circle locked (at 12.4 2) (size 0.4 0.4) (layers "F.Cu" "F.Paste" "F.Mask")
      (net 341 "ULPI1_D1") (pinfunction "PR68D") (pintype "bidirectional"))
    (pad "Y1" smd circle locked (at -12.4 2.8) (size 0.4 0.4) (layers "F.Cu" "F.Paste" "F.Mask")
      (net 260 "DDR3_CKE") (pinfunction "PL86B") (pintype "bidirectional"))
    (pad "Y2" smd circle locked (at -11.6 2.8) (size 0.4 0.4) (layers "F.Cu" "F.Paste" "F.Mask")
      (net 1 "GND") (pinfunction "GND") (pintype "passive"))
    (pad "Y3" smd circle locked (at -10.8 2.8) (size 0.4 0.4) (layers "F.Cu" "F.Paste" "F.Mask")
      (net 774 "unconnected-(U21G-PL65D-PadY3)") (pinfunction "PL65D") (pintype "bidirectional+no_connect"))
    (pad "Y4" smd circle locked (at -10 2.8) (size 0.4 0.4) (layers "F.Cu" "F.Paste" "F.Mask")
      (net 190 "DDR3_DQ2") (pinfunction "PL74A") (pintype "bidirectional"))
    (pad "Y5" smd circle locked (at -9.2 2.8) (size 0.4 0.4) (layers "F.Cu" "F.Paste" "F.Mask")
      (net 189 "DDR3_DQ5") (pinfunction "PL71C") (pintype "bidirectional"))
    (pad "Y6" smd circle locked (at -8.4 2.8) (size 0.4 0.4) (layers "F.Cu" "F.Paste" "F.Mask")
      (net 194 "DDR3_DQ6") (pinfunction "PL71B") (pintype "bidirectional"))
    (pad "Y7" smd circle locked (at -7.6 2.8) (size 0.4 0.4) (layers "F.Cu" "F.Paste" "F.Mask")
      (net 188 "DDR3_DQ7") (pinfunction "PL71A") (pintype "bidirectional"))
    (pad "Y10" smd circle locked (at -5.2 2.8) (size 0.4 0.4) (layers "F.Cu" "F.Paste" "F.Mask")
      (net 304 "/FPGA power supply/VCCAUX") (pinfunction "VCCAUX") (pintype "passive"))
    (pad "Y11" smd circle locked (at -4.4 2.8) (size 0.4 0.4) (layers "F.Cu" "F.Paste" "F.Mask")
      (net 1 "GND") (pinfunction "GND") (pintype "passive"))
    (pad "Y12" smd circle locked (at -3.6 2.8) (size 0.4 0.4) (layers "F.Cu" "F.Paste" "F.Mask")
      (net 211 "VCC1V2") (pinfunction "VCC") (pintype "passive"))
    (pad "Y13" smd circle locked (at -2.8 2.8) (size 0.4 0.4) (layers "F.Cu" "F.Paste" "F.Mask")
      (net 1 "GND") (pinfunction "GND") (pintype "passive"))
    (pad "Y14" smd circle locked (at -2 2.8) (size 0.4 0.4) (layers "F.Cu" "F.Paste" "F.Mask")
      (net 1 "GND") (pinfunction "GND") (pintype "passive"))
    (pad "Y15" smd circle locked (at -1.2 2.8) (size 0.4 0.4) (layers "F.Cu" "F.Paste" "F.Mask")
      (net 1 "GND") (pinfunction "GND") (pintype "passive"))
    (pad "Y16" smd circle locked (at -0.4 2.8) (size 0.4 0.4) (layers "F.Cu" "F.Paste" "F.Mask")
      (net 1 "GND") (pinfunction "GND") (pintype "passive"))
    (pad "Y17" smd circle locked (at 0.4 2.8) (size 0.4 0.4) (layers "F.Cu" "F.Paste" "F.Mask")
      (net 1 "GND") (pinfunction "GND") (pintype "passive"))
    (pad "Y18" smd circle locked (at 1.2 2.8) (size 0.4 0.4) (layers "F.Cu" "F.Paste" "F.Mask")
      (net 1 "GND") (pinfunction "GND") (pintype "passive"))
    (pad "Y19" smd circle locked (at 2 2.8) (size 0.4 0.4) (layers "F.Cu" "F.Paste" "F.Mask")
      (net 1 "GND") (pinfunction "GND") (pintype "passive"))
    (pad "Y20" smd circle locked (at 2.8 2.8) (size 0.4 0.4) (layers "F.Cu" "F.Paste" "F.Mask")
      (net 1 "GND") (pinfunction "GND") (pintype "passive"))
    (pad "Y21" smd circle locked (at 3.6 2.8) (size 0.4 0.4) (layers "F.Cu" "F.Paste" "F.Mask")
      (net 211 "VCC1V2") (pinfunction "VCC") (pintype "passive"))
    (pad "Y22" smd circle locked (at 4.4 2.8) (size 0.4 0.4) (layers "F.Cu" "F.Paste" "F.Mask")
      (net 1 "GND") (pinfunction "GND") (pintype "passive"))
    (pad "Y23" smd circle locked (at 5.2 2.8) (size 0.4 0.4) (layers "F.Cu" "F.Paste" "F.Mask")
      (net 304 "/FPGA power supply/VCCAUX") (pinfunction "VCCAUX") (pintype "passive"))
    (pad "Y26" smd circle locked (at 7.6 2.8) (size 0.4 0.4) (layers "F.Cu" "F.Paste" "F.Mask")
      (net 775 "unconnected-(U21E-PR71A-PadY26)") (pinfunction "PR71A") (pintype "bidirectional+no_connect"))
    (pad "Y27" smd circle locked (at 8.4 2.8) (size 0.4 0.4) (layers "F.Cu" "F.Paste" "F.Mask")
      (net 112 "HPM_STBY_RST_N") (pinfunction "PR71B") (pintype "bidirectional"))
    (pad "Y28" smd circle locked (at 9.2 2.8) (size 0.4 0.4) (layers "F.Cu" "F.Paste" "F.Mask")
      (net 320 "ULPI2_STP") (pinfunction "PR71C") (pintype "bidirectional"))
    (pad "Y29" smd circle locked (at 10 2.8) (size 0.4 0.4) (layers "F.Cu" "F.Paste" "F.Mask")
      (net 319 "ULPI_DIR") (pinfunction "PR74A") (pintype "bidirectional"))
    (pad "Y30" smd circle locked (at 10.8 2.8) (size 0.4 0.4) (layers "F.Cu" "F.Paste" "F.Mask")
      (net 318 "ULPI2_NXT") (pinfunction "PR65D") (pintype "bidirectional"))
    (pad "Y31" smd circle locked (at 11.6 2.8) (size 0.4 0.4) (layers "F.Cu" "F.Paste" "F.Mask")
      (net 1 "GND") (pinfunction "GND") (pintype "passive"))
    (pad "Y32" smd circle locked (at 12.4 2.8) (size 0.4 0.4) (layers "F.Cu" "F.Paste" "F.Mask")
      (net 317 "ULPI2_RESET") (pinfunction "PR86B") (pintype "bidirectional"))
  )
)
